# S9S_MB_2U (Grand Teton) — schematic parts with pin connectivity, parts 4256–4402 of 6093; source: Cadence DE-HDL packaged netlist (pstxprt.dat, pstxnet.dat, pstchip.dat)

R1955  Q_RES  10K 1% CHIP  pkg 0402LF  page 204 : 1 = P3V3_AUX ; 2 = FM_PCHHOT_N
R1958  Q_RES  10K 1% CHIP  pkg 0402LF  page 208 : 1 = P3V3_AUX ; 2 = PU_CLK_PFT_LOST_N
R1959  Q_RES  0 5% CHIP  pkg 0402LF  page 14 : 1 = H_CPU0_PMDOWN_PCH_R2 ; 2 = H_CPU0_PMDOWN_PCH_R
R1960  Q_RES  0 5% CHIP  pkg 0402LF  page 14 : 1 = H_CPU0_PMSYNC_PCH_R2 ; 2 = H_CPU0_PMSYNC_PCH_R
R1961  Q_RES  10K 1% CHIP  pkg 0402LF  page 202 : 1 = PGPPA_AUX ; 2 = ESPI_LFRAME_N_BMC_CS0_N
R1962  Q_RES  20K 1% EMPTY  pkg 0402LF  page 198 : 1 = FM_PCH_CONSENT_STRAP_N ; 2 = GND
R1995  Q_RES  33.2 1% CHIP  pkg 0402LF  page 223 : 1 = FM_PCH_SLP_S3_N ; 2 = FM_SLPS3_PLD_N
R1996  Q_RES  33.2 1% CHIP  pkg 0402LF  page 223 : 1 = FM_PCH_SLP_S4_N ; 2 = FM_SLPS4_PLD_N
R2071  Q_RES  0 5% EMPTY  pkg 0402LF  page 213 : 1 = FM_BMC_SUSACK_R_N ; 2 = FM_SUSACK_N
R2113  Q_RES  33.2 1% CHIP  pkg 0402LF  page 190 : 1 = RST_PCIE_PCH_DEV_BUF_M2_0_PERST ; 2 = RST_PCIE_PCH_DEV_0_N
R2114  Q_RES  0 5% CHIP  pkg 0402LF  page 191 : 1 = SMB_PCIE_E1S_ISO_EN_R2 ; 2 = SMB_PCIE_E1S_ISO_EN
R2121  Q_RES  4.7K 5% CHIP  pkg 0402LF  page 190 : 1 = P3V3_AUX ; 2 = RST_PCIE_PCH_DEV_BUF_M2_0_PERST
R2125  Q_RES  4.7K 5% CHIP  pkg 0402LF  page 191 : 1 = P3V3_AUX ; 2 = SMB_PCIE_E1S_ISO_EN
R2132  Q_RES  0 5% EMPTY  pkg 0402LF  page 202 : 1 = JTAG_TRC_PCH_PTI<6> ; 2 = FM_ESPI_PLD_R1_EN
R2133  Q_RES  1K 1% CHIP  pkg 0402LF  page 201 : 1 = P3V3_AUX ; 2 = PU_ESPI_ENABLE_STRAP
R2134  Q_RES  10K 1% CHIP  pkg 0402LF  page 201 : 1 = JTAG_TRC_PCH_PTI<6> ; 2 = GND
R2155  Q_RES  0 5% CHIP  pkg 0402LF  page 215 : 1 = FM_BMC_READY_R_PLD_N ; 2 = FM_BMC_READY_R_N
R2204  Q_RES  2.2K 5% EMPTY  pkg 0402LF  page 231 : 1 = P3V3_AUX ; 2 = SMB_PCIE0_3V3AUX_SCL
R2205  Q_RES  2.2K 5% EMPTY  pkg 0402LF  page 231 : 1 = P3V3_AUX ; 2 = SMB_PCIE0_3V3AUX_SDA
R2208  Q_RES  0 5% CHIP  pkg 0402LF  page 236 : 1 = SMB_S3M_CPU0_3V3AUX_SDA_R ; 2 = SMB_S3M_CPU0_3V3AUX_SDA
R2209  Q_RES  0 5% CHIP  pkg 0402LF  page 236 : 1 = SMB_S3M_CPU0_3V3AUX_SCL_R ; 2 = SMB_S3M_CPU0_3V3AUX_SCL
R2210  Q_RES  0 5% CHIP  pkg 0402LF  page 236 : 1 = SMB_S3M_CPU1_3V3AUX_SDA_R ; 2 = SMB_S3M_CPU1_3V3AUX_SDA
R2211  Q_RES  0 5% CHIP  pkg 0402LF  page 236 : 1 = SMB_S3M_CPU1_3V3AUX_SCL_R ; 2 = SMB_S3M_CPU1_3V3AUX_SCL
R2212  Q_RES  2.2K 5% EMPTY  pkg 0402LF  page 241 : 1 = SMB_S3M_CPU_3V3AUX_SCL ; 2 = P3V3_AUX
R2213  Q_RES  2.2K 5% EMPTY  pkg 0402LF  page 241 : 1 = SMB_S3M_CPU_3V3AUX_SDA ; 2 = P3V3_AUX
R2219  Q_RES  26.7K 1% CHIP  pkg 0402LF  page 306 : 1 = P12V_AUX ; 2 = A_P12V_STBY_ADR_TRIGGER
R2221  Q_RES  26.7K 1% CHIP  pkg 0402LF  page 306 : 1 = P12V_AUX ; 2 = A_P12V_STBY_FP_TRIGGER
R2222  Q_RES  1K 1% CHIP  pkg 0402LF  page 306 : 1 = A_P12V_STBY_FP_TRIGGER ; 2 = GND
R2227  Q_RES  1K 1% CHIP  pkg 0402LF  page 306 : 1 = A_P12V_STBY_ADR_TRIGGER ; 2 = GND
R2230  Q_RES  10K 1% CHIP  pkg 0402LF  page 306 : 1 = P3V3_AUX ; 2 = A_P12V_STBY_FPH_GATE
R2232  Q_RES  10K 1% CHIP  pkg 0402LF  page 195 : 1 = P1V05_PCH_AUX ; 2 = FAB_REV_ID0
R2233  Q_RES  10K 1% CHIP  pkg 0402LF  page 306 : 1 = P3V3_AUX ; 2 = FM_UV_ADR_TRIGGER_N
R2234  Q_RES  10K 1% EMPTY  pkg 0402LF  page 195 : 1 = P1V05_PCH_AUX ; 2 = FM_BOARD_SKU_ID4
R2235  Q_RES  1K 1% CHIP  pkg 0402LF  page 195 : 1 = FM_BOARD_SKU_ID4 ; 2 = GND
R2236  Q_RES  100K 1% EMPTY  pkg 0402LF  page 306 : 1 = P12V_AUX ; 2 = A_HSC_INAP
R2238  Q_RES  4.99K 1% EMPTY  pkg 0402LF  page 306 : 1 = A_HSC_INAP ; 2 = GND
R2240  Q_RES  10K 1% EMPTY  pkg 0402LF  page 195 : 1 = P1V05_PCH_AUX ; 2 = FM_BOARD_SKU_ID1
R2241  Q_RES  1K 1% CHIP  pkg 0402LF  page 195 : 1 = FM_BOARD_SKU_ID1 ; 2 = GND
R2242  Q_RES  10K 1% EMPTY  pkg 0402LF  page 195 : 1 = P1V05_PCH_AUX ; 2 = FM_BOARD_SKU_ID0
R2243  Q_RES  1K 1% CHIP  pkg 0402LF  page 195 : 1 = FM_BOARD_SKU_ID0 ; 2 = GND
R2244  Q_RES  10K 1% CHIP  pkg 0402LF  page 220 : 1 = ROT_P1_RST_IND_N_R ; 2 = P3V3_AUX
R2252  Q_RES  100K 1% EMPTY  pkg 0402LF  page 197 : 1 = PECI_MUX_SEL_R ; 2 = GND
R2253  Q_RES  4.75K 1% CHIP  pkg 0402LF  page 197 : 1 = P3V3_AUX ; 2 = PECI_MUX_SEL_R
R2255  Q_RES  0 5% CHIP  pkg 0402LF  page 197 : 1 = PECI_MUX_SEL_R ; 2 = FM_PECI_MUX_SEL_N
R2256  Q_RES  0 5% EMPTY  pkg 0402LF  page 240 : 1 = USB2_7_R_DP ; 2 = USB2_7_DP
R2257  Q_RES  0 5% EMPTY  pkg 0402LF  page 240 : 1 = USB2_7_R_DN ; 2 = USB2_7_DN
R2268  Q_RES  0 5% CHIP  pkg 0402LF  page 231 : 1 = RST_SMB_SWITCH_N ; 2 = PU_RST_SMB_PCIE0_N
R2282  Q_RES  10K 1% CHIP  pkg 0402LF  page 191 : 1 = P3V3_AUX ; 2 = E1S_0_PRSNT
R2287  Q_RES  10K 1% CHIP  pkg 0402LF  page 191 : 1 = P3V3_E1S_0 ; 2 = E1S_0_PERST1_CLKREQ_N
R2296  Q_RES  1K 1% CHIP  pkg 0402LF  page 191 : 1 = E1S_0_PWRDIS ; 2 = GND
R2304  Q_RES  10K 1% CHIP  pkg 0402LF  page 191 : 1 = P3V3_AUX ; 2 = E1S_0_PRSNT_N
R2308  Q_RES  10K 1% EMPTY  pkg 0402LF  page 236 : 1 = P3V3_AUX ; 2 = PCA9543_S3M_ADDR1
R2309  Q_RES  1K 1% CHIP  pkg 0402LF  page 236 : 1 = PCA9543_S3M_ADDR1 ; 2 = GND
R2310  Q_RES  10K 1% EMPTY  pkg 0402LF  page 236 : 1 = P3V3_AUX ; 2 = PCA9543_S3M_ADDR0
R2311  Q_RES  1K 1% CHIP  pkg 0402LF  page 236 : 1 = PCA9543_S3M_ADDR0 ; 2 = GND
R2312  Q_RES  10K 1% CHIP  pkg 0402LF  page 236 : 1 = P3V3_AUX ; 2 = PCA9545_S3M_INT_N
R2313  Q_RES  0 5% CHIP  pkg 0402LF  page 236 : 1 = RST_SMB_SWITCH_N ; 2 = RST_SMB_S3M_N
R2315  Q_RES  10K 1% CHIP  pkg 0402LF  page 236 : 1 = P3V3_AUX ; 2 = PCA9543_S3M_INT0_N
R2316  Q_RES  0 5% CHIP  pkg 0402LF  page 258 : 1 = PWRGD_P5V_AUX_R ; 2 = PWRGD_P5V_AUX
R2317  Q_RES  10K 1% CHIP  pkg 0402LF  page 191 : 1 = P3V3_E1S_0 ; 2 = PU_E1S_0_DUALPORT_EN_N
R2322  Q_RES  49.9 1% EMPTY  pkg 0402LF  page 274 : 1 = PVNN_TERM_CPU0 ; 2 = SVID_CLK0_CPU0_R
R2330  Q_RES  0 5% EMPTY  pkg 0402LF  page 306 : 1 = PWRGD_DSW_PWROK_R4 ; 2 = PWRGD_DSW_PWROK
R2332  Q_RES  2K 1% CHIP  pkg 0402LF  page 281 : 1 = FM_PVPP_HBM_CPU0_EN ; 2 = GND
R2338  Q_RES  10K 1% EMPTY  pkg 0402LF  page 282 : 1 = P3V3_AUX ; 2 = FM_PVNN_MAIN_CPU0_EN
R2339  Q_RES  22 5% CHIP  pkg 0402LF  page 218 : 1 = LED_CPU_RMCA_CATERR_R ; 2 = GND
R2342  Q_RES  10K 1% CHIP  pkg 0402LF  page 204 : 1 = P3V3_AUX ; 2 = FM_DEBUG_PORT_PRSNT_R_N
R2343  Q_RES  10K 1% EMPTY  pkg 0402LF  page 213 : 1 = P5V_AUX_VCC ; 2 = PWRGD_P5V_AUX
R2344  Q_RES  4.7K 5% CHIP  pkg 0402LF  page 213 : 1 = P3V3_AUX ; 2 = PWRGD_P5V_AUX_R1
R2345  Q_RES  49.9 1% EMPTY  pkg 0402LF  page 292 : 1 = PVNN_TERM_CPU1 ; 2 = SVID_CLK0_CPU1_R
R2346  Q_RES  4.7K 5% CHIP  pkg 0402LF  page 213 : 1 = P3V3_AUX ; 2 = PWRGD_P5V_AUX_R2
R2347  Q_RES  0 5% CHIP  pkg 0402LF  page 215 : 1 = FM_REMOTE_DEBUG_DET_R ; 2 = FM_REMOTE_DEBUG_DET
R2348  Q_RES  0 5% CHIP  pkg 0402LF  page 215 : 1 = FM_DEBUG_PORT_PRSNT_N ; 2 = FM_DEBUG_PORT_PRSNT_R_N
R2350  Q_RES  0 5% CHIP  pkg 0402LF  page 191 : 1 = FM_PS_EN_PLD_BUF1 ; 2 = FM_PS_EN_PLD_BUF1_R1
R2354  Q_RES  100 1% EMPTY  pkg 0402LF  page 292 : 1 = PVNN_TERM_CPU1 ; 2 = SVID_DIO0_CPU1_R
R2355  Q_RES  4.7K 5% EMPTY  pkg 0402LF  page 224 : 1 = P3V3_AUX ; 2 = FM_PS_EN_PLD_BUF1
R2356  Q_RES  10K 1% CHIP  pkg 0402LF  page 258 : 1 = P5V_AUX_VCC ; 2 = PWRGD_P5V_AUX_R
R2357  Q_RES  10K 1% CHIP  pkg 0402LF  page 262 : 1 = P3V3_AUX ; 2 = PWRGD_P1V05_PCH_AUX_R
R2358  Q_RES  0 5% CHIP  pkg 0402LF  page 263 : 1 = FM_PCH_P1V8_AUX_EN ; 2 = FM_PCH_P1V8_AUX_EN_R
R2359  Q_RES  10K 1% CHIP  pkg 0402LF  page 263 : 1 = P3V3_AUX ; 2 = PWRGD_P1V8_PCH_AUX_R
R2360  Q_RES  0 5% CHIP  pkg 0402LF  page 263 : 1 = PWRGD_P1V8_PCH_AUX_R ; 2 = PWRGD_P1V8_PCH_AUX
R2362  Q_RES  33.2 1% CHIP  pkg 0402LF  page 14 : 1 = H_CPU0_PMDOWN_CPU1_R ; 2 = H_CPU0_PMDOWN_CPU1_R1
R2363  Q_RES  10 1% CHIP  pkg 0402LF  page 202 : 1 = RST_ESPI_RESET_N ; 2 = RST_ESPI_RESET_N_R
R2365  Q_RES  1K 1% CHIP  pkg 0402LF  page 266 : 1 = P3V3_AUX ; 2 = PWRGD_PVCCIN_CPU0_R
R2366  Q_RES  0 5% CHIP  pkg 0402LF  page 266 : 1 = PWRGD_PVCCIN_CPU0 ; 2 = PWRGD_PVCCIN_CPU0_R
R2367  Q_RES  10K 1% EMPTY  pkg 0402LF  page 299 : 1 = P3V3_AUX ; 2 = FM_PVPP_HBM_CPU1_EN
R2368  Q_RES  150 1% CHIP  pkg 0402LF  page 266 : 1 = SVID_CLK0_CPU0_R ; 2 = SVID_CLK_PVCCIN_CPU0_R
R2369  Q_RES  0 5% CHIP  pkg 0402LF  page 266 : 1 = SVID_DIO0_CPU0_R ; 2 = SVID_DIO_PVCCIN_CPU0_R
R2370  Q_RES  0 5% CHIP  pkg 0402LF  page 266 : 1 = SVID_ALERT0_CPU0_R_N ; 2 = SVID_ALERT_PVCCIN_CPU0_R
R2371  Q_RES  33.2 1% CHIP  pkg 0402LF  page 266 : 1 = SMB_VR_3V3AUX_SCL_R3 ; 2 = SMB_CLK_PVCCIN_CPU0
R2372  Q_RES  33.2 1% CHIP  pkg 0402LF  page 266 : 1 = SMB_VR_3V3AUX_SDA_R3 ; 2 = SMB_DIO_PVCCIN_CPU0
R2373  Q_RES  1K 1% CHIP  pkg 0402LF  page 266 : 1 = P3V3_AUX ; 2 = IRQ_PVCCIN_CPU0_VRHOT_R_N
R2374  Q_RES  2K 1% CHIP  pkg 0402LF  page 299 : 1 = FM_PVPP_HBM_CPU1_EN ; 2 = GND
R2375  Q_RES  1K 1% CHIP  pkg 0402LF  page 266 : 1 = P3V3_AUX ; 2 = PVCCIN_CPU0_PIN_ALERT
R2376  Q_RES  0 5% CHIP  pkg 0402LF  page 266 : 1 = IRQ_PSYS_CRIT_N ; 2 = PVCCIN_CPU0_PIN_ALERT
R2377  Q_RES  1K 1% CHIP  pkg 0402LF  page 266 : 1 = P3V3_AUX ; 2 = PWRGD_PVCCFA_EHV_FIVRA_CPU0_R
R2379  Q_RES  0 5% CHIP  pkg 0402LF  page 266 : 1 = PWRGD_PVCCFA_EHV_FIVRA_CPU0 ; 2 = PWRGD_PVCCFA_EHV_FIVRA_CPU0_R
R2380  Q_RES  0 5% CHIP  pkg 0402LF  page 299 : 1 = PWRGD_PVPP_HBM_CPU1_R ; 2 = PWRGD_PVPP_HBM_CPU1
R2381  Q_RES  49.9 1% CHIP  pkg 0402LF  page 266 : 1 = SVID_CLK0_CPU0_R ; 2 = PVNN_TERM_CPU0
R2382  Q_RES  49.9 1% EMPTY  pkg 0402LF  page 266 : 1 = SVID_ALERT0_CPU0_R_N ; 2 = PVNN_TERM_CPU0
R2383  Q_RES  1K 1% CHIP  pkg 0402LF  page 274 : 1 = P3V3_AUX ; 2 = PWRGD_PVCCINFAON_CPU0_R
R2384  Q_RES  10K 1% EMPTY  pkg 0402LF  page 300 : 1 = P3V3_AUX ; 2 = FM_PVNN_MAIN_CPU1_EN
R2385  Q_RES  2K 1% CHIP  pkg 0402LF  page 300 : 1 = FM_PVNN_MAIN_CPU1_EN ; 2 = GND
R2386  Q_RES  100 1% EMPTY  pkg 0402LF  page 274 : 1 = PVNN_TERM_CPU0 ; 2 = SVID_DIO0_CPU0_R
R2387  Q_RES  0 5% CHIP  pkg 0402LF  page 300 : 1 = PWRGD_PVNN_MAIN_CPU1_R ; 2 = PWRGD_PVNN_MAIN_CPU1
R2388  Q_RES  0 5% CHIP  pkg 0402LF  page 274 : 1 = SVID_DIO0_CPU0_R ; 2 = SVID_DIO_PVCCINFAON_CPU0_R
R2389  Q_RES  0 5% CHIP  pkg 0402LF  page 274 : 1 = SVID_ALERT0_CPU0_R_N ; 2 = SVID_ALERT_PVCCINFAON_CPU0_R
R2390  Q_RES  0 5% CHIP  pkg 0402LF  page 274 : 1 = SMB_VR_3V3AUX_SCL_R2 ; 2 = SMB_CLK_PVCCINFAON_CPU0
R2391  Q_RES  0 5% CHIP  pkg 0402LF  page 274 : 1 = SMB_VR_3V3AUX_SDA_R2 ; 2 = SMB_DIO_PVCCINFAON_CPU0
R2392  Q_RES  1K 1% CHIP  pkg 0402LF  page 274 : 1 = P3V3_AUX ; 2 = PVCCINFAON_CPU0_VR_FAULT
R2393  Q_RES  1K 1% CHIP  pkg 0402LF  page 274 : 1 = P3V3_AUX ; 2 = PVCCINFAON_CPU0_PIN_ALERT
R2394  Q_RES  0 5% CHIP  pkg 0402LF  page 274 : 1 = FM_PVCCFA_EHV_CPU0_EN ; 2 = PVCCFA_EHV_CPU0_EN_R
R2396  Q_RES  1K 1% CHIP  pkg 0402LF  page 274 : 1 = P3V3_AUX ; 2 = PWRGD_PVCCFA_EHV_CPU0_R
R2397  Q_RES  0 5% CHIP  pkg 0402LF  page 274 : 1 = PWRGD_PVCCFA_EHV_CPU0 ; 2 = PWRGD_PVCCFA_EHV_CPU0_R
R2398  Q_RES  1K 1% CHIP  pkg 0402LF  page 274 : 1 = P3V3_AUX ; 2 = IRQ_PVCCFA_CPU0_VRHOT_R_N
R2399  Q_RES  150 1% CHIP  pkg 0402LF  page 278 : 1 = SVID_CLK1_CPU0_R ; 2 = SVID_CLK_PVCCD_HV_CPU0_R
R2400  Q_RES  0 5% CHIP  pkg 0402LF  page 278 : 1 = SVID_DIO1_CPU0_R ; 2 = SVID_DIO_PVCCD_HV_CPU0_R
R2401  Q_RES  0 5% CHIP  pkg 0402LF  page 278 : 1 = SVID_ALERT1_CPU0_R_N ; 2 = SVID_ALERT_PVCCD_HV_CPU0_R
R2402  Q_RES  0 5% CHIP  pkg 0402LF  page 278 : 1 = SMB_VR_3V3AUX_SCL_R2 ; 2 = SMB_CLK_PVCCD_HV_CPU0
R2403  Q_RES  0 5% CHIP  pkg 0402LF  page 278 : 1 = SMB_VR_3V3AUX_SDA_R2 ; 2 = SMB_DIO_PVCCD_HV_CPU0
R2404  Q_RES  1K 1% CHIP  pkg 0402LF  page 278 : 1 = P3V3_AUX ; 2 = IRQ_PVCCD_CPU0_VRHOT_LVC3_N
R2405  Q_RES  0 5% CHIP  pkg 0402LF  page 278 : 1 = IRQ_PVCCD_CPU0_VRHOT_LVC3_R_N ; 2 = IRQ_PVCCD_CPU0_VRHOT_LVC3_N
R2406  Q_RES  10K 1% EMPTY  pkg 0402LF  page 281 : 1 = P3V3_AUX ; 2 = FM_PVPP_HBM_CPU0_EN
R2407  Q_RES  10K 1% CHIP  pkg 0402LF  page 281 : 1 = P3V3_AUX ; 2 = PWRGD_PVPP_HBM_CPU0_R
R2408  Q_RES  0 5% CHIP  pkg 0402LF  page 281 : 1 = PWRGD_PVPP_HBM_CPU0_R ; 2 = PWRGD_PVPP_HBM_CPU0
R2409  Q_RES  10K 1% CHIP  pkg 0402LF  page 282 : 1 = P3V3_AUX ; 2 = PWRGD_PVNN_MAIN_CPU0_R
R2410  Q_RES  33.2 1% CHIP  pkg 0402LF  page 194 : 1 = SMB_M2_P0_1V8AUX_SDA_R ; 2 = SMB_M2_P0_1V8AUX_SDA
R2411  Q_RES  33.2 1% CHIP  pkg 0402LF  page 194 : 1 = SMB_M2_P0_1V8AUX_SCL_R ; 2 = SMB_M2_P0_1V8AUX_SCL
R2412  Q_RES  0 5% CHIP  pkg 0402LF  page 214 : 1 = PWRGD_DSW_PWROK ; 2 = PWRGD_DSW_PWROK_R3
R2413  Q_RES  0 5% CHIP  pkg 0402LF  page 240 : 1 = SMB_2_BMC_GPU_SCL ; 2 = SMB_PCIE2_3V3AUX_SCL_R0
R2414  Q_RES  0 5% CHIP  pkg 0402LF  page 240 : 1 = SMB_2_BMC_GPU_SDA ; 2 = SMB_PCIE2_3V3AUX_SDA_R0
R2415  Q_RES  0 5% CHIP  pkg 0402LF  page 240 : 1 = SMB_1_BMC_GPU_SCL ; 2 = SMB_PCIE3_3V3AUX_SCL_R
R2416  Q_RES  0 5% CHIP  pkg 0402LF  page 240 : 1 = SMB_1_BMC_GPU_SDA ; 2 = SMB_PCIE3_3V3AUX_SDA_R
R2417  Q_RES  33.2 1% CHIP  pkg 0402LF  page 240 : 1 = SMB_S3M_CPU_3V3AUX_SCL ; 2 = SMB_S3M_CPU_3V3AUX_SCL_R0
R2418  Q_RES  33.2 1% CHIP  pkg 0402LF  page 240 : 1 = SMB_S3M_CPU_3V3AUX_SDA ; 2 = SMB_S3M_CPU_3V3AUX_SDA_R0
R2419  Q_RES  33.2 1% CHIP  pkg 0402LF  page 240 : 1 = SMB_HOST_3V3AUX_SCL ; 2 = SMB_HOST_3V3AUX_SCL_R0
R2420  Q_RES  33.2 1% CHIP  pkg 0402LF  page 240 : 1 = SMB_HOST_3V3AUX_SDA ; 2 = SMB_HOST_3V3AUX_SDA_R0
R2421  Q_RES  33.2 1% CHIP  pkg 0402LF  page 240 : 1 = SMB_VR_SENSOR_3V3AUX_SCL ; 2 = SMB_VR_3V3AUX_SCL_R0
R2422  Q_RES  33.2 1% CHIP  pkg 0402LF  page 240 : 1 = SMB_VR_SENSOR_3V3AUX_SDA ; 2 = SMB_VR_3V3AUX_SDA_R0
R2423  Q_RES  33.2 1% CHIP  pkg 0402LF  page 240 : 1 = SMB_SML1_PMBUS_3V3AUX_PCH_SCL ; 2 = SMB_SML1_PMBUS_3V3AUX_PCH_SCL_R
R2424  Q_RES  33.2 1% CHIP  pkg 0402LF  page 240 : 1 = SMB_SML1_PMBUS_3V3AUX_PCH_SDA ; 2 = SMB_SML1_PMBUS_3V3AUX_PCH_SDA_R
R2425  Q_RES  33.2 1% CHIP  pkg 0402LF  page 240 : 1 = SMB_OCP_V3_2_3V3AUX_SCL ; 2 = SMB_OCP_V3_2_3V3AUX_SCL_R0
R2426  Q_RES  100 1% EMPTY  pkg 0402LF  page 191 : 1 = E1S_0_PERST1_CLKREQ_N ; 2 = GND
R2449  Q_RES  33.2 1% CHIP  pkg 0402LF  page 241 : 1 = SMB_VR_3V3AUX_SCL ; 2 = SMB_VR_3V3AUX_SCL_R1
R2450  Q_RES  33.2 1% CHIP  pkg 0402LF  page 241 : 1 = SMB_VR_3V3AUX_SDA ; 2 = SMB_VR_3V3AUX_SDA_R1
R2451  Q_RES  10K 1% EMPTY  pkg 0402LF  page 202 : 1 = P3V3_AUX ; 2 = FM_ESPI_PLD_R1_EN
R2452  Q_RES  0 5% CHIP  pkg 0402LF  page 214 : 1 = FM_ESPI_PLD_R_EN ; 2 = FM_ESPI_PLD_R1_EN
R2453  Q_RES  33.2 1% CHIP  pkg 0402LF  page 241 : 1 = SMB_VR_3V3AUX_SCL_R ; 2 = SMB_VR_3V3AUX_SCL_R2
